(kicad_pcb
	(version 20260206)
	(generator "pcbnew")
	(generator_version "10.0")
	(general
		(thickness 1.6)
		(legacy_teardrops no)
	)
	(paper "A4")
	(title_block
		(title "pdpb — Lightning_PDPB_BRD.brd")
		(comment 1 "Lightning (Wiwynn / Facebook NVMe JBOF) / footprints 1130-1136 of 1140")
	)
	(layers
		(0 "F.Cu" signal "TOP")
		(4 "In1.Cu" signal "L2GND")
		(6 "In2.Cu" signal "L3")
		(8 "In3.Cu" signal "L4VCC")
		(10 "In4.Cu" signal "L5VCC")
		(12 "In5.Cu" signal "L6")
		(14 "In6.Cu" signal "L7GND")
		(2 "B.Cu" signal "BOTTOM")
		(9 "F.Adhes" user "F.Adhesive")
		(11 "B.Adhes" user "B.Adhesive")
		(13 "F.Paste" user "Package Geometry/Pastemask Top")
		(15 "B.Paste" user "Package Geometry/Pastemask Bottom")
		(5 "F.SilkS" user "Ref Des/Silkscreen Top")
		(7 "B.SilkS" user "Ref Des/Silkscreen Bottom")
		(1 "F.Mask" user "Board Geometry/Soldermask Top")
		(3 "B.Mask" user "Board Geometry/Soldermask Bottom")
		(17 "Dwgs.User" user "User.Drawings")
		(19 "Cmts.User" user "User.Comments")
		(21 "Eco1.User" user "User.Eco1")
		(23 "Eco2.User" user "User.Eco2")
		(25 "Edge.Cuts" user "Board Geometry/Outline")
		(27 "Margin" user)
		(31 "F.CrtYd" user "Package Geometry/Place Bound Top")
		(29 "B.CrtYd" user "Package Geometry/Place Bound Bottom")
		(35 "F.Fab" user "Ref Des/Assembly Top")
		(33 "B.Fab" user "Ref Des/Assembly Bottom")
	)
	(footprint ""
		(layer "F.Cu")
		(at 102.616 -310.515 90)
		(property "Reference" "R9071"
			(at 0 0 90)
			(layer "F.SilkS")
			(hide yes)
			(effects
				(font
					(size 1.27 1.27)
				)
			)
		)
		(property "Value" "27R2F-GP"
			(at 0.064008 -3.993896 90)
			(unlocked yes)
			(layer "F.Fab")
			(hide yes)
			(effects
				(font
					(size 1.016 1.016)
					(thickness 0.1524)
				)
			)
		)
		(property "Device Type" "R402H16"
			(at 0.064008 -5.517896 90)
			(unlocked yes)
			(layer "F.Fab")
			(hide yes)
			(effects
				(font
					(size 1.016 1.016)
					(thickness 0.1524)
				)
			)
		)
		(duplicate_pad_numbers_are_jumpers no)
		(fp_line
			(start 0.508 -0.9398)
			(end -0.508 -0.9398)
			(stroke
				(width 0.1524)
				(type default)
			)
			(layer "F.SilkS")
		)
		(fp_line
			(start -0.508 -0.9398)
			(end -0.508 0.9398)
			(stroke
				(width 0.1524)
				(type default)
			)
			(layer "F.SilkS")
		)
		(fp_rect
			(start -0.508 0.9398)
			(end 0.508 -0.9398)
			(stroke
				(width 0)
				(type default)
			)
			(fill no)
			(layer "F.CrtYd")
		)
		(fp_rect
			(start -0.508 0.9398)
			(end 0.508 -0.9398)
			(stroke
				(width 0)
				(type default)
			)
			(fill no)
			(layer "F.Fab")
		)
		(pad "1" smd custom
			(at 0 -0.4445 90)
			(size 0.1397 0.1397)
			(layers "F.Cu" "F.Mask" "F.Paste")
			(net "PE_CLK_100M_DR1_1_R_P")
			(options
				(clearance outline)
				(anchor circle)
			)
			(primitives
				(gr_poly
					(pts
						(arc
							(start -0.1778 -0.2794)
							(mid -0.249642 -0.249642)
							(end -0.2794 -0.1778)
						)
						(arc
							(start -0.2794 0.1778)
							(mid -0.249642 0.249642)
							(end -0.1778 0.2794)
						)
						(arc
							(start 0.1778 0.2794)
							(mid 0.249642 0.249642)
							(end 0.2794 0.1778)
						)
						(arc
							(start 0.2794 -0.1778)
							(mid 0.249642 -0.249642)
							(end 0.1778 -0.2794)
						)
					)
					(width 0)
					(fill yes)
				)
			)
		)
		(pad "2" smd custom
			(at 0 0.4445 90)
			(size 0.1397 0.1397)
			(layers "F.Cu" "F.Mask" "F.Paste")
			(net "PE_CLK100M_DR1_1_P")
			(options
				(clearance outline)
				(anchor circle)
			)
			(primitives
				(gr_poly
					(pts
						(arc
							(start -0.1778 -0.2794)
							(mid -0.249642 -0.249642)
							(end -0.2794 -0.1778)
						)
						(arc
							(start -0.2794 0.1778)
							(mid -0.249642 0.249642)
							(end -0.1778 0.2794)
						)
						(arc
							(start 0.1778 0.2794)
							(mid 0.249642 0.249642)
							(end 0.2794 0.1778)
						)
						(arc
							(start 0.2794 -0.1778)
							(mid 0.249642 -0.249642)
							(end 0.1778 -0.2794)
						)
					)
					(width 0)
					(fill yes)
				)
			)
		)
	)
	(footprint ""
		(layer "F.Cu")
		(at 19.910298 -470.984072 -90)
		(property "Reference" "C9528"
			(at 0 0 270)
			(layer "F.SilkS")
			(hide yes)
			(effects
				(font
					(size 1.27 1.27)
				)
			)
		)
		(property "Value" "SCD1U16V2KX-3GP"
			(at 1.1811 -2.7051 270)
			(unlocked yes)
			(layer "F.Fab")
			(hide yes)
			(effects
				(font
					(size 1.016 1.016)
					(thickness 0.1524)
				)
			)
		)
		(property "Device Type" "C402H22"
			(at 1.1811 -4.2291 270)
			(unlocked yes)
			(layer "F.Fab")
			(hide yes)
			(effects
				(font
					(size 1.016 1.016)
					(thickness 0.1524)
				)
			)
		)
		(duplicate_pad_numbers_are_jumpers no)
		(fp_rect
			(start -0.4318 0.9525)
			(end 0.4318 -0.9525)
			(stroke
				(width 0)
				(type default)
			)
			(fill no)
			(layer "F.CrtYd")
		)
		(fp_rect
			(start -0.4318 0.9525)
			(end 0.4318 -0.9525)
			(stroke
				(width 0)
				(type default)
			)
			(fill no)
			(layer "F.Fab")
		)
		(pad "1" smd custom
			(at 0 -0.4445 270)
			(size 0.1524 0.1524)
			(layers "F.Cu" "F.Mask" "F.Paste")
			(net "P3V3")
			(options
				(clearance outline)
				(anchor circle)
			)
			(primitives
				(gr_poly
					(pts
						(arc
							(start 0.3048 -0.2032)
							(mid 0.275042 -0.275042)
							(end 0.2032 -0.3048)
						)
						(arc
							(start -0.2032 -0.3048)
							(mid -0.275042 -0.275042)
							(end -0.3048 -0.2032)
						)
						(arc
							(start -0.3048 0.2032)
							(mid -0.275042 0.275042)
							(end -0.2032 0.3048)
						)
						(arc
							(start 0.2032 0.3048)
							(mid 0.275042 0.275042)
							(end 0.3048 0.2032)
						)
					)
					(width 0)
					(fill yes)
				)
			)
		)
		(pad "2" smd custom
			(at 0 0.4445 270)
			(size 0.1524 0.1524)
			(layers "F.Cu" "F.Mask" "F.Paste")
			(net "GND")
			(options
				(clearance outline)
				(anchor circle)
			)
			(primitives
				(gr_poly
					(pts
						(arc
							(start 0.3048 -0.2032)
							(mid 0.275042 -0.275042)
							(end 0.2032 -0.3048)
						)
						(arc
							(start -0.2032 -0.3048)
							(mid -0.275042 -0.275042)
							(end -0.3048 -0.2032)
						)
						(arc
							(start -0.3048 0.2032)
							(mid -0.275042 0.275042)
							(end -0.2032 0.3048)
						)
						(arc
							(start 0.2032 0.3048)
							(mid 0.275042 0.275042)
							(end 0.3048 0.2032)
						)
					)
					(width 0)
					(fill yes)
				)
			)
		)
	)
	(footprint ""
		(layer "F.Cu")
		(at 234.061 -246.634 -90)
		(property "Reference" "R9401"
			(at 0 0 270)
			(layer "F.SilkS")
			(hide yes)
			(effects
				(font
					(size 1.27 1.27)
				)
			)
		)
		(property "Value" "100R2J-2-GP"
			(at 0.064008 -3.993896 270)
			(unlocked yes)
			(layer "F.Fab")
			(hide yes)
			(effects
				(font
					(size 1.016 1.016)
					(thickness 0.1524)
				)
			)
		)
		(property "Device Type" "R402H14"
			(at 0.064008 -5.517896 270)
			(unlocked yes)
			(layer "F.Fab")
			(hide yes)
			(effects
				(font
					(size 1.016 1.016)
					(thickness 0.1524)
				)
			)
		)
		(duplicate_pad_numbers_are_jumpers no)
		(fp_line
			(start -0.508 -0.9398)
			(end -0.508 0.9398)
			(stroke
				(width 0.1524)
				(type default)
			)
			(layer "F.SilkS")
		)
		(fp_line
			(start 0.508 -0.9398)
			(end -0.508 -0.9398)
			(stroke
				(width 0.1524)
				(type default)
			)
			(layer "F.SilkS")
		)
		(fp_rect
			(start -0.508 0.9398)
			(end 0.508 -0.9398)
			(stroke
				(width 0)
				(type default)
			)
			(fill no)
			(layer "F.CrtYd")
		)
		(fp_rect
			(start -0.508 0.9398)
			(end 0.508 -0.9398)
			(stroke
				(width 0)
				(type default)
			)
			(fill no)
			(layer "F.Fab")
		)
		(pad "1" smd custom
			(at 0 -0.4445 270)
			(size 0.1397 0.1397)
			(layers "F.Cu" "F.Mask" "F.Paste")
			(net "P3V3")
			(options
				(clearance outline)
				(anchor circle)
			)
			(primitives
				(gr_poly
					(pts
						(arc
							(start -0.1778 -0.2794)
							(mid -0.249642 -0.249642)
							(end -0.2794 -0.1778)
						)
						(arc
							(start -0.2794 0.1778)
							(mid -0.249642 0.249642)
							(end -0.1778 0.2794)
						)
						(arc
							(start 0.1778 0.2794)
							(mid 0.249642 0.249642)
							(end 0.2794 0.1778)
						)
						(arc
							(start 0.2794 -0.1778)
							(mid 0.249642 -0.249642)
							(end 0.1778 -0.2794)
						)
					)
					(width 0)
					(fill yes)
				)
			)
		)
		(pad "2" smd custom
			(at 0 0.4445 270)
			(size 0.1397 0.1397)
			(layers "F.Cu" "F.Mask" "F.Paste")
			(net "DRV_ACT_2")
			(options
				(clearance outline)
				(anchor circle)
			)
			(primitives
				(gr_poly
					(pts
						(arc
							(start -0.1778 -0.2794)
							(mid -0.249642 -0.249642)
							(end -0.2794 -0.1778)
						)
						(arc
							(start -0.2794 0.1778)
							(mid -0.249642 0.249642)
							(end -0.1778 0.2794)
						)
						(arc
							(start 0.1778 0.2794)
							(mid 0.249642 0.249642)
							(end 0.2794 0.1778)
						)
						(arc
							(start 0.2794 -0.1778)
							(mid 0.249642 -0.249642)
							(end 0.1778 -0.2794)
						)
					)
					(width 0)
					(fill yes)
				)
			)
		)
	)
	(footprint ""
		(layer "F.Cu")
		(at 225.1075 -142.42161 90)
		(property "Reference" "R9915"
			(at 0 0 90)
			(layer "F.SilkS")
			(hide yes)
			(effects
				(font
					(size 1.27 1.27)
				)
			)
		)
		(property "Value" "47KR2J-2-GP"
			(at 0.064008 -3.993896 90)
			(unlocked yes)
			(layer "F.Fab")
			(hide yes)
			(effects
				(font
					(size 1.016 1.016)
					(thickness 0.1524)
				)
			)
		)
		(property "Device Type" "R402H16"
			(at 0.064008 -5.517896 90)
			(unlocked yes)
			(layer "F.Fab")
			(hide yes)
			(effects
				(font
					(size 1.016 1.016)
					(thickness 0.1524)
				)
			)
		)
		(duplicate_pad_numbers_are_jumpers no)
		(fp_line
			(start 0.508 -0.9398)
			(end -0.508 -0.9398)
			(stroke
				(width 0.1524)
				(type default)
			)
			(layer "F.SilkS")
		)
		(fp_line
			(start -0.508 -0.9398)
			(end -0.508 0.9398)
			(stroke
				(width 0.1524)
				(type default)
			)
			(layer "F.SilkS")
		)
		(fp_rect
			(start -0.508 0.9398)
			(end 0.508 -0.9398)
			(stroke
				(width 0)
				(type default)
			)
			(fill no)
			(layer "F.CrtYd")
		)
		(fp_rect
			(start -0.508 0.9398)
			(end 0.508 -0.9398)
			(stroke
				(width 0)
				(type default)
			)
			(fill no)
			(layer "F.Fab")
		)
		(pad "1" smd custom
			(at 0 -0.4445 90)
			(size 0.1397 0.1397)
			(layers "F.Cu" "F.Mask" "F.Paste")
			(net "P3V3")
			(options
				(clearance outline)
				(anchor circle)
			)
			(primitives
				(gr_poly
					(pts
						(arc
							(start -0.1778 -0.2794)
							(mid -0.249642 -0.249642)
							(end -0.2794 -0.1778)
						)
						(arc
							(start -0.2794 0.1778)
							(mid -0.249642 0.249642)
							(end -0.1778 0.2794)
						)
						(arc
							(start 0.1778 0.2794)
							(mid 0.249642 0.249642)
							(end 0.2794 0.1778)
						)
						(arc
							(start 0.2794 -0.1778)
							(mid 0.249642 -0.249642)
							(end 0.1778 -0.2794)
						)
					)
					(width 0)
					(fill yes)
				)
			)
		)
		(pad "2" smd custom
			(at 0 0.4445 90)
			(size 0.1397 0.1397)
			(layers "F.Cu" "F.Mask" "F.Paste")
			(net "ATTN_LED_DR3_N")
			(options
				(clearance outline)
				(anchor circle)
			)
			(primitives
				(gr_poly
					(pts
						(arc
							(start -0.1778 -0.2794)
							(mid -0.249642 -0.249642)
							(end -0.2794 -0.1778)
						)
						(arc
							(start -0.2794 0.1778)
							(mid -0.249642 0.249642)
							(end -0.1778 0.2794)
						)
						(arc
							(start 0.1778 0.2794)
							(mid 0.249642 0.249642)
							(end 0.2794 0.1778)
						)
						(arc
							(start 0.2794 -0.1778)
							(mid 0.249642 -0.249642)
							(end 0.1778 -0.2794)
						)
					)
					(width 0)
					(fill yes)
				)
			)
		)
	)
	(footprint ""
		(layer "F.Cu")
		(at 32.131 -184.531 -90)
		(property "Reference" "R403"
			(at 0 0 270)
			(layer "F.SilkS")
			(hide yes)
			(effects
				(font
					(size 1.27 1.27)
				)
			)
		)
		(property "Value" "0R2J-2-GP"
			(at 0.064008 -3.993896 270)
			(unlocked yes)
			(layer "F.Fab")
			(hide yes)
			(effects
				(font
					(size 1.016 1.016)
					(thickness 0.1524)
				)
			)
		)
		(property "Device Type" "R402H16"
			(at 0.064008 -5.517896 270)
			(unlocked yes)
			(layer "F.Fab")
			(hide yes)
			(effects
				(font
					(size 1.016 1.016)
					(thickness 0.1524)
				)
			)
		)
		(duplicate_pad_numbers_are_jumpers no)
		(fp_line
			(start -0.508 -0.9398)
			(end -0.508 0.9398)
			(stroke
				(width 0.1524)
				(type default)
			)
			(layer "F.SilkS")
		)
		(fp_line
			(start 0.508 -0.9398)
			(end -0.508 -0.9398)
			(stroke
				(width 0.1524)
				(type default)
			)
			(layer "F.SilkS")
		)
		(fp_rect
			(start -0.508 0.9398)
			(end 0.508 -0.9398)
			(stroke
				(width 0)
				(type default)
			)
			(fill no)
			(layer "F.CrtYd")
		)
		(fp_rect
			(start -0.508 0.9398)
			(end 0.508 -0.9398)
			(stroke
				(width 0)
				(type default)
			)
			(fill no)
			(layer "F.Fab")
		)
		(pad "1" smd custom
			(at 0 -0.4445 270)
			(size 0.1397 0.1397)
			(layers "F.Cu" "F.Mask" "F.Paste")
			(net "SCL_DR8_R")
			(options
				(clearance outline)
				(anchor circle)
			)
			(primitives
				(gr_poly
					(pts
						(arc
							(start -0.1778 -0.2794)
							(mid -0.249642 -0.249642)
							(end -0.2794 -0.1778)
						)
						(arc
							(start -0.2794 0.1778)
							(mid -0.249642 0.249642)
							(end -0.1778 0.2794)
						)
						(arc
							(start 0.1778 0.2794)
							(mid 0.249642 0.249642)
							(end 0.2794 0.1778)
						)
						(arc
							(start 0.2794 -0.1778)
							(mid 0.249642 -0.249642)
							(end 0.1778 -0.2794)
						)
					)
					(width 0)
					(fill yes)
				)
			)
		)
		(pad "2" smd custom
			(at 0 0.4445 270)
			(size 0.1397 0.1397)
			(layers "F.Cu" "F.Mask" "F.Paste")
			(net "SCL_DR8")
			(options
				(clearance outline)
				(anchor circle)
			)
			(primitives
				(gr_poly
					(pts
						(arc
							(start -0.1778 -0.2794)
							(mid -0.249642 -0.249642)
							(end -0.2794 -0.1778)
						)
						(arc
							(start -0.2794 0.1778)
							(mid -0.249642 0.249642)
							(end -0.1778 0.2794)
						)
						(arc
							(start 0.1778 0.2794)
							(mid 0.249642 0.249642)
							(end 0.2794 0.1778)
						)
						(arc
							(start 0.2794 -0.1778)
							(mid 0.249642 -0.249642)
							(end 0.1778 -0.2794)
						)
					)
					(width 0)
					(fill yes)
				)
			)
		)
	)
	(footprint ""
		(layer "F.Cu")
		(at 85.471 -208.026 90)
		(property "Reference" "R9119"
			(at 0 0 90)
			(layer "F.SilkS")
			(hide yes)
			(effects
				(font
					(size 1.27 1.27)
				)
			)
		)
		(property "Value" "4K7R2F-GP"
			(at 0.064008 -3.993896 90)
			(unlocked yes)
			(layer "F.Fab")
			(hide yes)
			(effects
				(font
					(size 1.016 1.016)
					(thickness 0.1524)
				)
			)
		)
		(property "Device Type" "R402H16"
			(at 0.064008 -5.517896 90)
			(unlocked yes)
			(layer "F.Fab")
			(hide yes)
			(effects
				(font
					(size 1.016 1.016)
					(thickness 0.1524)
				)
			)
		)
		(duplicate_pad_numbers_are_jumpers no)
		(fp_line
			(start 0.508 -0.9398)
			(end -0.508 -0.9398)
			(stroke
				(width 0.1524)
				(type default)
			)
			(layer "F.SilkS")
		)
		(fp_line
			(start -0.508 -0.9398)
			(end -0.508 0.9398)
			(stroke
				(width 0.1524)
				(type default)
			)
			(layer "F.SilkS")
		)
		(fp_rect
			(start -0.508 0.9398)
			(end 0.508 -0.9398)
			(stroke
				(width 0)
				(type default)
			)
			(fill no)
			(layer "F.CrtYd")
		)
		(fp_rect
			(start -0.508 0.9398)
			(end 0.508 -0.9398)
			(stroke
				(width 0)
				(type default)
			)
			(fill no)
			(layer "F.Fab")
		)
		(pad "1" smd custom
			(at 0 -0.4445 90)
			(size 0.1397 0.1397)
			(layers "F.Cu" "F.Mask" "F.Paste")
			(net "VDD_DIFF_3")
			(options
				(clearance outline)
				(anchor circle)
			)
			(primitives
				(gr_poly
					(pts
						(arc
							(start -0.1778 -0.2794)
							(mid -0.249642 -0.249642)
							(end -0.2794 -0.1778)
						)
						(arc
							(start -0.2794 0.1778)
							(mid -0.249642 0.249642)
							(end -0.1778 0.2794)
						)
						(arc
							(start 0.1778 0.2794)
							(mid 0.249642 0.249642)
							(end 0.2794 0.1778)
						)
						(arc
							(start 0.2794 -0.1778)
							(mid 0.249642 -0.249642)
							(end 0.1778 -0.2794)
						)
					)
					(width 0)
					(fill yes)
				)
			)
		)
		(pad "2" smd custom
			(at 0 0.4445 90)
			(size 0.1397 0.1397)
			(layers "F.Cu" "F.Mask" "F.Paste")
			(net "CLK_BUF_EU3_SMB_A0_TRI")
			(options
				(clearance outline)
				(anchor circle)
			)
			(primitives
				(gr_poly
					(pts
						(arc
							(start -0.1778 -0.2794)
							(mid -0.249642 -0.249642)
							(end -0.2794 -0.1778)
						)
						(arc
							(start -0.2794 0.1778)
							(mid -0.249642 0.249642)
							(end -0.1778 0.2794)
						)
						(arc
							(start 0.1778 0.2794)
							(mid 0.249642 0.249642)
							(end 0.2794 0.1778)
						)
						(arc
							(start 0.2794 -0.1778)
							(mid 0.249642 -0.249642)
							(end 0.1778 -0.2794)
						)
					)
					(width 0)
					(fill yes)
				)
			)
		)
	)
	(footprint ""
		(layer "F.Cu")
		(at 43.282108 -37.961062 180)
		(property "Reference" "SR1140"
			(at 0 0 180)
			(layer "F.SilkS")
			(hide yes)
			(effects
				(font
					(size 1.27 1.27)
				)
			)
		)
		(property "Value" "4K7R2J-2-GP"
			(at 0.064008 -3.993896 180)
			(unlocked yes)
			(layer "F.Fab")
			(hide yes)
			(effects
				(font
					(size 1.016 1.016)
					(thickness 0.1524)
				)
			)
		)
		(property "Device Type" "R402H16"
			(at 0.064008 -5.517896 180)
			(unlocked yes)
			(layer "F.Fab")
			(hide yes)
			(effects
				(font
					(size 1.016 1.016)
					(thickness 0.1524)
				)
			)
		)
		(duplicate_pad_numbers_are_jumpers no)
		(fp_line
			(start 0.508 -0.9398)
			(end -0.508 -0.9398)
			(stroke
				(width 0.1524)
				(type default)
			)
			(layer "F.SilkS")
		)
		(fp_line
			(start -0.508 -0.9398)
			(end -0.508 0.9398)
			(stroke
				(width 0.1524)
				(type default)
			)
			(layer "F.SilkS")
		)
		(fp_rect
			(start -0.508 0.9398)
			(end 0.508 -0.9398)
			(stroke
				(width 0)
				(type default)
			)
			(fill no)
			(layer "F.CrtYd")
		)
		(fp_rect
			(start -0.508 0.9398)
			(end 0.508 -0.9398)
			(stroke
				(width 0)
				(type default)
			)
			(fill no)
			(layer "F.Fab")
		)
		(pad "1" smd custom
			(at 0 -0.4445 180)
			(size 0.1397 0.1397)
			(layers "F.Cu" "F.Mask" "F.Paste")
			(net "P3V3")
			(options
				(clearance outline)
				(anchor circle)
			)
			(primitives
				(gr_poly
					(pts
						(arc
							(start -0.1778 -0.2794)
							(mid -0.249642 -0.249642)
							(end -0.2794 -0.1778)
						)
						(arc
							(start -0.2794 0.1778)
							(mid -0.249642 0.249642)
							(end -0.1778 0.2794)
						)
						(arc
							(start 0.1778 0.2794)
							(mid 0.249642 0.249642)
							(end 0.2794 0.1778)
						)
						(arc
							(start 0.2794 -0.1778)
							(mid 0.249642 -0.249642)
							(end 0.1778 -0.2794)
						)
					)
					(width 0)
					(fill yes)
				)
			)
		)
		(pad "2" smd custom
			(at 0 0.4445 180)
			(size 0.1397 0.1397)
			(layers "F.Cu" "F.Mask" "F.Paste")
			(net "SSD_ACT_DR9")
			(options
				(clearance outline)
				(anchor circle)
			)
			(primitives
				(gr_poly
					(pts
						(arc
							(start -0.1778 -0.2794)
							(mid -0.249642 -0.249642)
							(end -0.2794 -0.1778)
						)
						(arc
							(start -0.2794 0.1778)
							(mid -0.249642 0.249642)
							(end -0.1778 0.2794)
						)
						(arc
							(start 0.1778 0.2794)
							(mid 0.249642 0.249642)
							(end 0.2794 0.1778)
						)
						(arc
							(start 0.2794 -0.1778)
							(mid 0.249642 -0.249642)
							(end 0.1778 -0.2794)
						)
					)
					(width 0)
					(fill yes)
				)
			)
		)
	)
)
